(kicad_pcb
	(version 20260206)
	(generator "pcbnew")
	(generator_version "10.0")
	(general
		(thickness 1.6)
		(legacy_teardrops no)
	)
	(paper "A4")
	(title_block
		(title "v1-chassis-manager — T6M_CM_d_v01_1031_1645.brd")
		(comment 1 "Open CloudServer (Microsoft) / footprints 53-58 of 2512")
	)
	(layers
		(0 "F.Cu" signal "TOP")
		(4 "In1.Cu" signal "GND1")
		(6 "In2.Cu" signal "IN1")
		(8 "In3.Cu" signal "VCC1")
		(10 "In4.Cu" signal "VCC2")
		(12 "In5.Cu" signal "GND2")
		(14 "In6.Cu" signal "IN2")
		(16 "In7.Cu" signal "IN3")
		(18 "In8.Cu" signal "GND3")
		(2 "B.Cu" signal "BOTTOM")
		(9 "F.Adhes" user "F.Adhesive")
		(11 "B.Adhes" user "B.Adhesive")
		(13 "F.Paste" user "Package Geometry/Pastemask Top")
		(15 "B.Paste" user "Package Geometry/Pastemask Bottom")
		(5 "F.SilkS" user "Ref Des/Silkscreen Top")
		(7 "B.SilkS" user "Ref Des/Silkscreen Bottom")
		(1 "F.Mask" user "Board Geometry/Soldermask Top")
		(3 "B.Mask" user "Board Geometry/Soldermask Bottom")
		(17 "Dwgs.User" user "User.Drawings")
		(19 "Cmts.User" user "User.Comments")
		(21 "Eco1.User" user "User.Eco1")
		(23 "Eco2.User" user "User.Eco2")
		(25 "Edge.Cuts" user "Board Geometry/Outline")
		(27 "Margin" user)
		(31 "F.CrtYd" user "Package Geometry/Place Bound Top")
		(29 "B.CrtYd" user "Package Geometry/Place Bound Bottom")
		(35 "F.Fab" user "Ref Des/Assembly Top")
		(33 "B.Fab" user "Ref Des/Assembly Bottom")
	)
	(footprint ""
		(layer "F.Cu")
		(at 146.913346 -150.244048 90)
		(property "Reference" "R303"
			(at -4.65455 0.049276 90)
			(unlocked yes)
			(layer "F.SilkS")
			(effects
				(font
					(size 0.7874 0.5842)
					(thickness 0.1524)
				)
				(justify left)
			)
		)
		(property "Value" ""
			(at 0 0 90)
			(layer "F.Fab")
			(effects
				(font
					(size 1.27 1.27)
				)
			)
		)
		(duplicate_pad_numbers_are_jumpers no)
		(fp_line
			(start 0.7874 -0.4064)
			(end 0.7874 0.4064)
			(stroke
				(width 0.1524)
				(type default)
			)
			(layer "F.SilkS")
		)
		(fp_line
			(start -0.7874 -0.4064)
			(end 0.7874 -0.4064)
			(stroke
				(width 0.1524)
				(type default)
			)
			(layer "F.SilkS")
		)
		(fp_line
			(start 0.7874 0.4064)
			(end -0.7874 0.4064)
			(stroke
				(width 0.1524)
				(type default)
			)
			(layer "F.SilkS")
		)
		(fp_line
			(start -0.7874 0.4064)
			(end -0.7874 -0.4064)
			(stroke
				(width 0.1524)
				(type default)
			)
			(layer "F.SilkS")
		)
		(fp_poly
			(pts
				(xy -0.508 0.2794) (xy -0.508 0.2286) (xy -0.635 0.2286) (xy -0.635 -0.254) (xy -0.5334 -0.254)
				(xy -0.5334 -0.2794) (xy 0.5334 -0.2794) (xy 0.5334 -0.254) (xy 0.635 -0.254) (xy 0.635 0.254) (xy 0.5334 0.254)
				(xy 0.5334 0.2794)
			)
			(stroke
				(width 0)
				(type default)
			)
			(fill no)
			(layer "F.CrtYd")
		)
		(pad "1" smd rect
			(at 0.40005 0 90)
			(size 0.4572 0.508)
			(layers "F.Cu" "F.Mask" "F.Paste")
			(net "PCIE_SW_EEPROM_DAT")
		)
		(pad "2" smd rect
			(at -0.40005 0 90)
			(size 0.4572 0.508)
			(layers "F.Cu" "F.Mask" "F.Paste")
			(net "P3V3_NODE1")
		)
	)
	(footprint ""
		(layer "F.Cu")
		(at 81.374996 -74.733912 90)
		(property "Reference" "R103"
			(at -16.266414 1.877568 90)
			(unlocked yes)
			(layer "F.SilkS")
			(effects
				(font
					(size 0.7874 0.5842)
					(thickness 0.1524)
				)
				(justify left)
			)
		)
		(property "Value" ""
			(at 0 0 90)
			(layer "F.Fab")
			(effects
				(font
					(size 1.27 1.27)
				)
			)
		)
		(duplicate_pad_numbers_are_jumpers no)
		(fp_line
			(start 0.7874 -0.4064)
			(end 0.7874 0.4064)
			(stroke
				(width 0.1524)
				(type default)
			)
			(layer "F.SilkS")
		)
		(fp_line
			(start -0.7874 -0.4064)
			(end 0.7874 -0.4064)
			(stroke
				(width 0.1524)
				(type default)
			)
			(layer "F.SilkS")
		)
		(fp_line
			(start 0.7874 0.4064)
			(end -0.7874 0.4064)
			(stroke
				(width 0.1524)
				(type default)
			)
			(layer "F.SilkS")
		)
		(fp_line
			(start -0.7874 0.4064)
			(end -0.7874 -0.4064)
			(stroke
				(width 0.1524)
				(type default)
			)
			(layer "F.SilkS")
		)
		(fp_poly
			(pts
				(xy -0.508 0.2794) (xy -0.508 0.2286) (xy -0.635 0.2286) (xy -0.635 -0.254) (xy -0.5334 -0.254)
				(xy -0.5334 -0.2794) (xy 0.5334 -0.2794) (xy 0.5334 -0.254) (xy 0.635 -0.254) (xy 0.635 0.254) (xy 0.5334 0.254)
				(xy 0.5334 0.2794)
			)
			(stroke
				(width 0)
				(type default)
			)
			(fill no)
			(layer "F.CrtYd")
		)
		(pad "1" smd rect
			(at 0.40005 0 90)
			(size 0.4572 0.508)
			(layers "F.Cu" "F.Mask" "F.Paste")
			(net "P1V05_NODE1")
		)
		(pad "2" smd rect
			(at -0.40005 0 90)
			(size 0.4572 0.508)
			(layers "F.Cu" "F.Mask" "F.Paste")
			(net "A_CPU_NODE1_AE64_PU")
		)
	)
	(footprint ""
		(layer "F.Cu")
		(at 78.823058 -154.740356 180)
		(property "Reference" "PU1"
			(at -2.442972 -1.271016 90)
			(unlocked yes)
			(layer "F.SilkS")
			(effects
				(font
					(size 0.7874 0.5842)
					(thickness 0.1524)
				)
				(justify left)
			)
		)
		(property "Value" ""
			(at 0 0 180)
			(layer "F.Fab")
			(effects
				(font
					(size 1.27 1.27)
				)
			)
		)
		(duplicate_pad_numbers_are_jumpers no)
		(fp_line
			(start 2.055622 0.25019)
			(end 2.563622 0.25019)
			(stroke
				(width 0.1524)
				(type default)
			)
			(layer "F.SilkS")
		)
		(fp_line
			(start 1.575054 1.575054)
			(end 1.575054 1.143)
			(stroke
				(width 0.1524)
				(type default)
			)
			(layer "F.SilkS")
		)
		(fp_line
			(start 1.575054 -1.0668)
			(end 1.575054 -1.575054)
			(stroke
				(width 0.1524)
				(type default)
			)
			(layer "F.SilkS")
		)
		(fp_line
			(start 1.575054 -1.575054)
			(end 1.0414 -1.575054)
			(stroke
				(width 0.1524)
				(type default)
			)
			(layer "F.SilkS")
		)
		(fp_line
			(start 1.0414 1.575054)
			(end 1.575054 1.575054)
			(stroke
				(width 0.1524)
				(type default)
			)
			(layer "F.SilkS")
		)
		(fp_line
			(start -0.255778 -2.350262)
			(end -0.255778 -2.045462)
			(stroke
				(width 0.1524)
				(type default)
			)
			(layer "F.SilkS")
		)
		(fp_line
			(start -0.750062 2.043938)
			(end -0.750062 2.348738)
			(stroke
				(width 0.1524)
				(type default)
			)
			(layer "F.SilkS")
		)
		(fp_line
			(start -1.0668 -1.575054)
			(end -1.575054 -1.575054)
			(stroke
				(width 0.1524)
				(type default)
			)
			(layer "F.SilkS")
		)
		(fp_line
			(start -1.575054 1.575054)
			(end -1.0922 1.575054)
			(stroke
				(width 0.1524)
				(type default)
			)
			(layer "F.SilkS")
		)
		(fp_line
			(start -1.575054 1.0922)
			(end -1.575054 1.575054)
			(stroke
				(width 0.1524)
				(type default)
			)
			(layer "F.SilkS")
		)
		(fp_line
			(start -1.575054 -1.575054)
			(end -1.575054 -1.0414)
			(stroke
				(width 0.1524)
				(type default)
			)
			(layer "F.SilkS")
		)
		(fp_poly
			(pts
				(xy -1.729232 -1.368552) (xy -2.266442 -2.443226) (xy -2.803906 -1.905762)
			)
			(stroke
				(width 0)
				(type default)
			)
			(fill yes)
			(layer "F.SilkS")
		)
		(fp_poly
			(pts
				(xy -1.575054 1.575054) (xy -0.9398 1.575054) (xy -0.9398 1.9558) (xy 0.9398 1.9558) (xy 0.9398 1.575054)
				(xy 1.575054 1.575054) (xy 1.575054 0.9398) (xy 1.9558 0.9398) (xy 1.9558 -0.9398) (xy 1.575054 -0.9398)
				(xy 1.575054 -1.575054) (xy 0.9398 -1.575054) (xy 0.9398 -1.9558) (xy -0.9398 -1.9558) (xy -0.9398 -1.575054)
				(xy -1.575054 -1.575054) (xy -1.575054 -0.9398) (xy -1.9558 -0.9398) (xy -1.9558 0.9398) (xy -1.575054 0.9398)
			)
			(stroke
				(width 0)
				(type default)
			)
			(fill no)
			(layer "F.CrtYd")
		)
		(fp_line
			(start 2.055622 0.25019)
			(end 2.563622 0.25019)
			(stroke
				(width 0.1)
				(type default)
			)
			(layer "F.Fab")
		)
		(fp_line
			(start 1.575054 1.575054)
			(end -1.575054 1.575054)
			(stroke
				(width 0.1)
				(type default)
			)
			(layer "F.Fab")
		)
		(fp_line
			(start 1.575054 -1.575054)
			(end 1.575054 1.575054)
			(stroke
				(width 0.1)
				(type default)
			)
			(layer "F.Fab")
		)
		(fp_line
			(start -0.255778 -2.350262)
			(end -0.255778 -2.045462)
			(stroke
				(width 0.1)
				(type default)
			)
			(layer "F.Fab")
		)
		(fp_line
			(start -0.750062 2.043938)
			(end -0.750062 2.348738)
			(stroke
				(width 0.1)
				(type default)
			)
			(layer "F.Fab")
		)
		(fp_line
			(start -1.575054 1.575054)
			(end -1.575054 -1.575054)
			(stroke
				(width 0.1)
				(type default)
			)
			(layer "F.Fab")
		)
		(fp_line
			(start -1.575054 -1.575054)
			(end 1.575054 -1.575054)
			(stroke
				(width 0.1)
				(type default)
			)
			(layer "F.Fab")
		)
		(fp_poly
			(pts
				(xy -2.100072 -0.750062) (xy -3.240024 -1.130046) (xy -3.240024 -0.370078)
			)
			(stroke
				(width 0)
				(type default)
			)
			(fill yes)
			(layer "F.Fab")
		)
		(fp_text user "9"
			(at 2.078736 1.508506 0)
			(unlocked yes)
			(layer "F.SilkS")
			(effects
				(font
					(size 0.635 0.4064)
					(thickness 0.1524)
				)
				(justify left)
			)
		)
		(fp_text user "12"
			(at 2.001012 -0.81788 270)
			(unlocked yes)
			(layer "F.SilkS")
			(effects
				(font
					(size 0.635 0.4064)
					(thickness 0.1524)
				)
				(justify left)
			)
		)
		(fp_text user "16"
			(at -0.981456 -1.984502 0)
			(unlocked yes)
			(layer "F.SilkS")
			(effects
				(font
					(size 0.635 0.4064)
					(thickness 0.1524)
				)
				(justify left)
			)
		)
		(fp_text user "5"
			(at -1.280922 2.128774 270)
			(unlocked yes)
			(layer "F.SilkS")
			(effects
				(font
					(size 0.635 0.4064)
					(thickness 0.1524)
				)
				(justify left)
			)
		)
		(fp_text user "9"
			(at 1.767586 1.584325 180)
			(unlocked yes)
			(layer "F.Fab")
			(effects
				(font
					(size 0.78994 0.579882)
					(thickness 0.000001)
				)
				(justify left)
			)
		)
		(fp_text user "12"
			(at 1.708912 -1.514475 180)
			(unlocked yes)
			(layer "F.Fab")
			(effects
				(font
					(size 0.78994 0.579882)
					(thickness 0.000001)
				)
				(justify left)
			)
		)
		(fp_text user "5"
			(at -1.737868 2.295525 180)
			(unlocked yes)
			(layer "F.Fab")
			(effects
				(font
					(size 0.78994 0.579882)
					(thickness 0.000001)
				)
				(justify left)
			)
		)
		(fp_text user "16"
			(at -2.457958 -2.225675 180)
			(unlocked yes)
			(layer "F.Fab")
			(effects
				(font
					(size 0.78994 0.579882)
					(thickness 0.000001)
				)
				(justify left)
			)
		)
		(pad "1" smd rect
			(at -1.474978 -0.750062 270)
			(size 0.254 0.8382)
			(layers "F.Cu" "F.Mask" "F.Paste")
			(net "P5V_STB_NODE1_FB")
		)
		(pad "2" smd rect
			(at -1.474978 -0.249936 270)
			(size 0.254 0.8382)
			(layers "F.Cu" "F.Mask" "F.Paste")
			(net "P5V_STB_NODE1_VREG5")
		)
		(pad "3" smd rect
			(at -1.474978 0.249936 270)
			(size 0.254 0.8382)
			(layers "F.Cu" "F.Mask" "F.Paste")
			(net "P5V_STB_NODE1_SS")
		)
		(pad "4" smd rect
			(at -1.474978 0.750062 270)
			(size 0.254 0.8382)
			(layers "F.Cu" "F.Mask" "F.Paste")
			(net "GND")
		)
		(pad "5" smd rect
			(at -0.750062 1.474978 180)
			(size 0.254 0.8382)
			(layers "F.Cu" "F.Mask" "F.Paste")
			(net "PWRGD_NODE1_P5V_STB_PG")
		)
		(pad "6" smd rect
			(at -0.249936 1.474978 180)
			(size 0.254 0.8382)
			(layers "F.Cu" "F.Mask" "F.Paste")
			(net "P5V_STB_NODE1_EN_P")
		)
		(pad "7" smd rect
			(at 0.249936 1.474978 180)
			(size 0.254 0.8382)
			(layers "F.Cu" "F.Mask" "F.Paste")
			(net "GND")
		)
		(pad "8" smd rect
			(at 0.750062 1.474978 180)
			(size 0.254 0.8382)
			(layers "F.Cu" "F.Mask" "F.Paste")
			(net "GND")
		)
		(pad "9" smd rect
			(at 1.474978 0.750062 270)
			(size 0.254 0.8382)
			(layers "F.Cu" "F.Mask" "F.Paste")
			(net "SW_P5V_STB_NODE1_PH")
		)
		(pad "10" smd rect
			(at 1.474978 0.249936 270)
			(size 0.254 0.8382)
			(layers "F.Cu" "F.Mask" "F.Paste")
			(net "SW_P5V_STB_NODE1_PH")
		)
		(pad "11" smd rect
			(at 1.474978 -0.249936 270)
			(size 0.254 0.8382)
			(layers "F.Cu" "F.Mask" "F.Paste")
			(net "SW_P5V_STB_NODE1_PH")
		)
		(pad "12" smd rect
			(at 1.474978 -0.750062 270)
			(size 0.254 0.8382)
			(layers "F.Cu" "F.Mask" "F.Paste")
			(net "SW_P5V_STB_NODE1_BT")
		)
		(pad "13" smd rect
			(at 0.750062 -1.474978 180)
			(size 0.254 0.8382)
			(layers "F.Cu" "F.Mask" "F.Paste")
			(net "P12V_AUX")
		)
		(pad "14" smd rect
			(at 0.249936 -1.474978 180)
			(size 0.254 0.8382)
			(layers "F.Cu" "F.Mask" "F.Paste")
			(net "P12V_AUX")
		)
		(pad "15" smd rect
			(at -0.249936 -1.474978 180)
			(size 0.254 0.8382)
			(layers "F.Cu" "F.Mask" "F.Paste")
			(net "P12V_AUX")
		)
		(pad "16" smd rect
			(at -0.750062 -1.474978 180)
			(size 0.254 0.8382)
			(layers "F.Cu" "F.Mask" "F.Paste")
			(net "P5V_STB_NODE1")
		)
		(pad "TH" smd rect
			(at 0 0 270)
			(size 1.7018 1.7018)
			(layers "F.Cu" "F.Mask" "F.Paste")
			(net "GND")
		)
		(zone
			(layer "F.Cu")
			(hatch none 0.5)
			(connect_pads
				(clearance 0)
			)
			(min_thickness 0.25)
			(keepout
				(tracks not_allowed)
				(vias allowed)
				(pads allowed)
				(copperpour not_allowed)
				(footprints allowed)
			)
			(placement
				(enabled no)
				(sheetname "")
			)
			(fill
				(thermal_gap 0.5)
				(thermal_bridge_width 0.5)
				(island_removal_mode 0)
			)
			(polygon
				(pts
					(xy 79.813658 -153.749756) (xy 77.832458 -153.749756) (xy 77.832458 -155.730956) (xy 77.885798 -155.730956)
					(xy 77.908658 -155.640278) (xy 77.908658 -153.825956) (xy 79.737458 -153.825956) (xy 79.737458 -155.629356)
					(xy 79.813658 -155.629356)
				)
			)
		)
		(zone
			(layer "F.Cu")
			(hatch none 0.5)
			(connect_pads
				(clearance 0)
			)
			(min_thickness 0.25)
			(keepout
				(tracks allowed)
				(vias not_allowed)
				(pads allowed)
				(copperpour not_allowed)
				(footprints allowed)
			)
			(placement
				(enabled no)
				(sheetname "")
			)
			(fill
				(thermal_gap 0.5)
				(thermal_bridge_width 0.5)
				(island_removal_mode 0)
			)
			(polygon
				(pts
					(xy 79.813658 -153.749756) (xy 77.832458 -153.749756) (xy 77.832458 -155.730956) (xy 79.813658 -155.730956)
					(xy 79.813658 -155.654756) (xy 77.908658 -155.654756) (xy 77.908658 -153.825956) (xy 79.737458 -153.825956)
					(xy 79.737458 -155.629356) (xy 79.813658 -155.629356)
				)
			)
		)
	)
	(footprint ""
		(layer "F.Cu")
		(at 149.947122 -165.95979 180)
		(property "Reference" "R1158"
			(at 0.244094 1.953006 0)
			(unlocked yes)
			(layer "F.SilkS")
			(effects
				(font
					(size 0.635 0.4064)
					(thickness 0.1524)
				)
				(justify left)
			)
		)
		(property "Value" ""
			(at 0 0 180)
			(layer "F.Fab")
			(effects
				(font
					(size 1.27 1.27)
				)
			)
		)
		(duplicate_pad_numbers_are_jumpers no)
		(fp_line
			(start 0.7874 0.4064)
			(end -0.7874 0.4064)
			(stroke
				(width 0.1524)
				(type default)
			)
			(layer "F.SilkS")
		)
		(fp_line
			(start 0.7874 -0.4064)
			(end 0.7874 0.4064)
			(stroke
				(width 0.1524)
				(type default)
			)
			(layer "F.SilkS")
		)
		(fp_line
			(start -0.7874 0.4064)
			(end -0.7874 -0.4064)
			(stroke
				(width 0.1524)
				(type default)
			)
			(layer "F.SilkS")
		)
		(fp_line
			(start -0.7874 -0.4064)
			(end 0.7874 -0.4064)
			(stroke
				(width 0.1524)
				(type default)
			)
			(layer "F.SilkS")
		)
		(fp_poly
			(pts
				(xy -0.508 0.2794) (xy -0.508 0.2286) (xy -0.635 0.2286) (xy -0.635 -0.254) (xy -0.5334 -0.254)
				(xy -0.5334 -0.2794) (xy 0.5334 -0.2794) (xy 0.5334 -0.254) (xy 0.635 -0.254) (xy 0.635 0.254) (xy 0.5334 0.254)
				(xy 0.5334 0.2794)
			)
			(stroke
				(width 0)
				(type default)
			)
			(fill no)
			(layer "F.CrtYd")
		)
		(pad "1" smd rect
			(at 0.40005 0 180)
			(size 0.4572 0.508)
			(layers "F.Cu" "F.Mask" "F.Paste")
			(net "UART_RTS_P3_N")
		)
		(pad "2" smd rect
			(at -0.40005 0 180)
			(size 0.4572 0.508)
			(layers "F.Cu" "F.Mask" "F.Paste")
			(net "GND")
		)
	)
	(footprint ""
		(layer "F.Cu")
		(at 155.257246 -161.2138 90)
		(property "Reference" "R590"
			(at -7.98703 19.88947 90)
			(unlocked yes)
			(layer "F.SilkS")
			(effects
				(font
					(size 0.7874 0.5842)
					(thickness 0.1524)
				)
				(justify left)
			)
		)
		(property "Value" ""
			(at 0 0 90)
			(layer "F.Fab")
			(effects
				(font
					(size 1.27 1.27)
				)
			)
		)
		(duplicate_pad_numbers_are_jumpers no)
		(fp_line
			(start 0.7874 -0.4064)
			(end 0.7874 0.4064)
			(stroke
				(width 0.1524)
				(type default)
			)
			(layer "F.SilkS")
		)
		(fp_line
			(start -0.7874 -0.4064)
			(end 0.7874 -0.4064)
			(stroke
				(width 0.1524)
				(type default)
			)
			(layer "F.SilkS")
		)
		(fp_line
			(start 0.7874 0.4064)
			(end -0.7874 0.4064)
			(stroke
				(width 0.1524)
				(type default)
			)
			(layer "F.SilkS")
		)
		(fp_line
			(start -0.7874 0.4064)
			(end -0.7874 -0.4064)
			(stroke
				(width 0.1524)
				(type default)
			)
			(layer "F.SilkS")
		)
		(fp_poly
			(pts
				(xy -0.508 0.2794) (xy -0.508 0.2286) (xy -0.635 0.2286) (xy -0.635 -0.254) (xy -0.5334 -0.254)
				(xy -0.5334 -0.2794) (xy 0.5334 -0.2794) (xy 0.5334 -0.254) (xy 0.635 -0.254) (xy 0.635 0.254) (xy 0.5334 0.254)
				(xy 0.5334 0.2794)
			)
			(stroke
				(width 0)
				(type default)
			)
			(fill no)
			(layer "F.CrtYd")
		)
		(pad "1" smd rect
			(at 0.40005 0 90)
			(size 0.4572 0.508)
			(layers "F.Cu" "F.Mask" "F.Paste")
			(net "FM_CPLD_NODE1_CPU_RESET_L")
		)
		(pad "2" smd rect
			(at -0.40005 0 90)
			(size 0.4572 0.508)
			(layers "F.Cu" "F.Mask" "F.Paste")
			(net "PLT_RST_LAN2_N")
		)
	)
	(footprint ""
		(layer "F.Cu")
		(at 39.266368 -6.550914 90)
		(property "Reference" "PR37"
			(at -1.42494 -9.37895 90)
			(unlocked yes)
			(layer "F.SilkS")
			(effects
				(font
					(size 0.7874 0.5842)
					(thickness 0.1524)
				)
				(justify left)
			)
		)
		(property "Value" ""
			(at 0 0 90)
			(layer "F.Fab")
			(effects
				(font
					(size 1.27 1.27)
				)
			)
		)
		(duplicate_pad_numbers_are_jumpers no)
		(fp_line
			(start 0.7874 -0.4064)
			(end 0.7874 0.4064)
			(stroke
				(width 0.1524)
				(type default)
			)
			(layer "F.SilkS")
		)
		(fp_line
			(start -0.7874 -0.4064)
			(end 0.7874 -0.4064)
			(stroke
				(width 0.1524)
				(type default)
			)
			(layer "F.SilkS")
		)
		(fp_line
			(start 0.7874 0.4064)
			(end -0.7874 0.4064)
			(stroke
				(width 0.1524)
				(type default)
			)
			(layer "F.SilkS")
		)
		(fp_line
			(start -0.7874 0.4064)
			(end -0.7874 -0.4064)
			(stroke
				(width 0.1524)
				(type default)
			)
			(layer "F.SilkS")
		)
		(fp_poly
			(pts
				(xy -0.508 0.2794) (xy -0.508 0.2286) (xy -0.635 0.2286) (xy -0.635 -0.254) (xy -0.5334 -0.254)
				(xy -0.5334 -0.2794) (xy 0.5334 -0.2794) (xy 0.5334 -0.254) (xy 0.635 -0.254) (xy 0.635 0.254) (xy 0.5334 0.254)
				(xy 0.5334 0.2794)
			)
			(stroke
				(width 0)
				(type default)
			)
			(fill no)
			(layer "F.CrtYd")
		)
		(pad "1" smd rect
			(at 0.40005 0 90)
			(size 0.4572 0.508)
			(layers "F.Cu" "F.Mask" "F.Paste")
			(net "PV_VDDR_NODE1_VID1")
		)
		(pad "2" smd rect
			(at -0.40005 0 90)
			(size 0.4572 0.508)
			(layers "F.Cu" "F.Mask" "F.Paste")
			(net "GND")
		)
	)
)
